# TIMECARD (Time Appliance Project (Time Card)) — schematic netlist excerpt (pin names and nets, part order shuffled) for the footprints in the layout excerpt that follows; sources: Cadence DE-HDL packaged netlist, KiCad conversion of R4006-B0001-02_R01.brd

SP48  NULL  pkg DUMMY  page 34
TP199  TP_PIONT  pkg TP010CT020B030_PTH  page 25 : \1\ = IO_L20P_35
C86  CAPACITOR  18PF 5%  pkg SMC_0201R  page 24 : \1\ = SG ; \2\ = UNNAMED_524_CAPACITOR_I7_2
R40  RESISTOR  20KOHM 1%  pkg SMC_0402R_H016  page 28 : \1\ = UNNAMED_517_CAPACITOR_I30_1 ; \2\ = XP3R3V_FB_R_TO_AGND

(kicad_pcb
	(version 20260206)
	(generator "pcbnew")
	(generator_version "10.0")
	(general
		(thickness 1.6)
		(legacy_teardrops no)
	)
	(paper "A4")
	(title_block
		(title "timecard-production-celestica-r4006 — R4006-B0001-02_R01.brd")
		(comment 1 "Time Appliance Project (Time Card) / footprints 341-344 of 1113")
	)
	(layers
		(0 "F.Cu" signal "TOP")
		(4 "In1.Cu" signal "L02_GND1")
		(6 "In2.Cu" signal "L03_SIG1")
		(8 "In3.Cu" signal "L04_GND2")
		(10 "In4.Cu" signal "L05_VCC1")
		(12 "In5.Cu" signal "L06_VCC2")
		(14 "In6.Cu" signal "L07_GND3")
		(16 "In7.Cu" signal "L08_SIG2")
		(18 "In8.Cu" signal "L09_GND4")
		(2 "B.Cu" signal "BOTTOM")
		(9 "F.Adhes" user "F.Adhesive")
		(11 "B.Adhes" user "B.Adhesive")
		(13 "F.Paste" user "Package Geometry/Pastemask Top")
		(15 "B.Paste" user "Package Geometry/Pastemask Bottom")
		(5 "F.SilkS" user "Ref Des/Silkscreen Top")
		(7 "B.SilkS" user "Ref Des/Silkscreen Bottom")
		(1 "F.Mask" user "Board Geometry/Soldermask Top")
		(3 "B.Mask" user "Board Geometry/Soldermask Bottom")
		(17 "Dwgs.User" user "User.Drawings")
		(19 "Cmts.User" user "User.Comments")
		(21 "Eco1.User" user "User.Eco1")
		(23 "Eco2.User" user "User.Eco2")
		(25 "Edge.Cuts" user "Board Geometry/Outline")
		(27 "Margin" user)
		(31 "F.CrtYd" user "Package Geometry/Place Bound Top")
		(29 "B.CrtYd" user "Package Geometry/Place Bound Bottom")
		(35 "F.Fab" user "Ref Des/Assembly Top")
		(33 "B.Fab" user "Ref Des/Assembly Bottom")
	)
	(footprint ""
		(layer "F.Cu")
		(at 89.9922 -97.3582 180)
		(property "Reference" "R40"
			(at -1.778 -2.45237 0)
			(unlocked yes)
			(layer "F.SilkS")
			(effects
				(font
					(size 0.7874 0.5842)
					(thickness 0.1524)
				)
			)
		)
		(property "Value" "VAL*"
			(at 0.02032 2.13233 180)
			(unlocked yes)
			(layer "F.Fab")
			(hide yes)
			(effects
				(font
					(size 0.7874 0.5842)
					(thickness 0.1524)
				)
			)
		)
		(property "Tolerance" "TOL*"
			(at 0.044704 3.05435 180)
			(unlocked yes)
			(layer "Cmts.User")
			(hide yes)
			(effects
				(font
					(size 0.7874 0.5842)
					(thickness 0.1524)
				)
			)
		)
		(property "User Part Number" "PARTNUM*"
			(at 0.02032 4.024884 180)
			(unlocked yes)
			(layer "Cmts.User")
			(hide yes)
			(effects
				(font
					(size 0.7874 0.5842)
					(thickness 0.1524)
				)
			)
		)
		(property "Device Type" "RESISTOR-G155-12002-01,20KOHM,A"
			(at 0.008382 1.210564 180)
			(unlocked yes)
			(layer "F.Fab")
			(hide yes)
			(effects
				(font
					(size 0.7874 0.5842)
					(thickness 0.1524)
				)
			)
		)
		(duplicate_pad_numbers_are_jumpers no)
		(fp_line
			(start 1.143 0.5588)
			(end 1.143 -0.5588)
			(stroke
				(width 0.1)
				(type default)
			)
			(layer "F.SilkS")
		)
		(fp_line
			(start 1.143 -0.5588)
			(end -1.143 -0.5588)
			(stroke
				(width 0.1)
				(type default)
			)
			(layer "F.SilkS")
		)
		(fp_line
			(start -1.143 0.5588)
			(end 1.143 0.5588)
			(stroke
				(width 0.1)
				(type default)
			)
			(layer "F.SilkS")
		)
		(fp_line
			(start -1.143 -0.5588)
			(end -1.143 0.5588)
			(stroke
				(width 0.1)
				(type default)
			)
			(layer "F.SilkS")
		)
		(fp_rect
			(start 1.143 -0.5588)
			(end -1.143 0.5588)
			(stroke
				(width 0)
				(type default)
			)
			(fill no)
			(layer "F.CrtYd")
		)
		(fp_line
			(start 0.508 0.3048)
			(end 0.508 -0.3048)
			(stroke
				(width 0.1)
				(type default)
			)
			(layer "F.Fab")
		)
		(fp_line
			(start 0.508 -0.3048)
			(end -0.508 -0.3048)
			(stroke
				(width 0.1)
				(type default)
			)
			(layer "F.Fab")
		)
		(fp_line
			(start -0.508 0.3048)
			(end 0.508 0.3048)
			(stroke
				(width 0.1)
				(type default)
			)
			(layer "F.Fab")
		)
		(fp_line
			(start -0.508 -0.3048)
			(end -0.508 0.3048)
			(stroke
				(width 0.1)
				(type default)
			)
			(layer "F.Fab")
		)
		(pad "1" smd rect
			(at -0.5334 0 180)
			(size 0.7112 0.6096)
			(layers "F.Cu" "F.Mask" "F.Paste")
			(net "UNNAMED_517_CAPACITOR_I30_1")
		)
		(pad "2" smd rect
			(at 0.5334 0 180)
			(size 0.7112 0.6096)
			(layers "F.Cu" "F.Mask" "F.Paste")
			(net "XP3R3V_FB_R_TO_AGND")
		)
		(zone
			(layer "F.Cu")
			(hatch none 0.5)
			(connect_pads
				(clearance 0)
			)
			(min_thickness 0.25)
			(keepout
				(tracks allowed)
				(vias not_allowed)
				(pads allowed)
				(copperpour not_allowed)
				(footprints allowed)
			)
			(placement
				(enabled no)
				(sheetname "")
			)
			(fill
				(thermal_gap 0.5)
				(thermal_bridge_width 0.5)
				(island_removal_mode 0)
			)
			(polygon
				(pts
					(xy 89.916 -97.0534) (xy 90.0684 -97.0534) (xy 90.0684 -97.663) (xy 89.916 -97.663)
				)
			)
		)
	)
	(footprint ""
		(layer "F.Cu")
		(at 32.512 -96.266 180)
		(property "Reference" "C86"
			(at -2.70637 -1.016 90)
			(unlocked yes)
			(layer "F.SilkS")
			(effects
				(font
					(size 0.7874 0.5842)
					(thickness 0.1524)
				)
			)
		)
		(property "Value" "VAL*"
			(at 0.193548 2.13614 180)
			(unlocked yes)
			(layer "F.Fab")
			(hide yes)
			(effects
				(font
					(size 0.7874 0.5842)
					(thickness 0.1524)
				)
			)
		)
		(property "Tolerance" "TOL*"
			(at 0.216154 3.1496 180)
			(unlocked yes)
			(layer "Cmts.User")
			(hide yes)
			(effects
				(font
					(size 0.7874 0.5842)
					(thickness 0.1524)
				)
			)
		)
		(property "Device Type" "CAPACITOR-G104-0A180-FJ,18PF,5%"
			(at 0.184404 1.180592 180)
			(unlocked yes)
			(layer "F.Fab")
			(hide yes)
			(effects
				(font
					(size 0.7874 0.5842)
					(thickness 0.1524)
				)
			)
		)
		(property "User Part Number" "PARTNUM*"
			(at 0.216154 4.185666 180)
			(unlocked yes)
			(layer "Cmts.User")
			(hide yes)
			(effects
				(font
					(size 0.7874 0.5842)
					(thickness 0.1524)
				)
			)
		)
		(duplicate_pad_numbers_are_jumpers no)
		(fp_line
			(start 0.671322 0.4445)
			(end -0.671322 0.4445)
			(stroke
				(width 0.1)
				(type default)
			)
			(layer "F.SilkS")
		)
		(fp_line
			(start 0.671322 -0.4445)
			(end 0.671322 0.4445)
			(stroke
				(width 0.1)
				(type default)
			)
			(layer "F.SilkS")
		)
		(fp_line
			(start -0.671322 0.4445)
			(end -0.671322 -0.4445)
			(stroke
				(width 0.1)
				(type default)
			)
			(layer "F.SilkS")
		)
		(fp_line
			(start -0.671322 -0.4445)
			(end 0.671322 -0.4445)
			(stroke
				(width 0.1)
				(type default)
			)
			(layer "F.SilkS")
		)
		(fp_rect
			(start 0.671322 0.4445)
			(end -0.671322 -0.4445)
			(stroke
				(width 0)
				(type default)
			)
			(fill no)
			(layer "F.CrtYd")
		)
		(fp_line
			(start 0.31496 0.1651)
			(end 0.31496 -0.1651)
			(stroke
				(width 0.1)
				(type default)
			)
			(layer "F.Fab")
		)
		(fp_line
			(start 0.31496 -0.1651)
			(end -0.31496 -0.1651)
			(stroke
				(width 0.1)
				(type default)
			)
			(layer "F.Fab")
		)
		(fp_line
			(start -0.31496 0.1651)
			(end 0.31496 0.1651)
			(stroke
				(width 0.1)
				(type default)
			)
			(layer "F.Fab")
		)
		(fp_line
			(start -0.31496 -0.1651)
			(end -0.31496 0.1651)
			(stroke
				(width 0.1)
				(type default)
			)
			(layer "F.Fab")
		)
		(pad "1" smd rect
			(at -0.264922 0 180)
			(size 0.3048 0.381)
			(layers "F.Cu" "F.Mask" "F.Paste")
			(net "SG")
		)
		(pad "2" smd rect
			(at 0.264922 0 180)
			(size 0.3048 0.381)
			(layers "F.Cu" "F.Mask" "F.Paste")
			(net "UNNAMED_524_CAPACITOR_I7_2")
		)
		(zone
			(layer "F.Cu")
			(hatch none 0.5)
			(connect_pads
				(clearance 0)
			)
			(min_thickness 0.25)
			(keepout
				(tracks allowed)
				(vias not_allowed)
				(pads allowed)
				(copperpour not_allowed)
				(footprints allowed)
			)
			(placement
				(enabled no)
				(sheetname "")
			)
			(fill
				(thermal_gap 0.5)
				(thermal_bridge_width 0.5)
				(island_removal_mode 0)
			)
			(polygon
				(pts
					(xy 32.399478 -96.4565) (xy 32.399478 -96.0755) (xy 32.624522 -96.0755) (xy 32.624522 -96.4565)
				)
			)
		)
	)
	(footprint ""
		(layer "F.Cu")
		(at 69.469 -129.794)
		(property "Reference" "SP48"
			(at 0 0 0)
			(layer "F.SilkS")
			(hide yes)
			(effects
				(font
					(size 1.27 1.27)
				)
			)
		)
		(property "Value" ""
			(at 0 0 0)
			(layer "F.Fab")
			(effects
				(font
					(size 1.27 1.27)
				)
			)
		)
		(duplicate_pad_numbers_are_jumpers no)
	)
	(footprint ""
		(layer "F.Cu")
		(at 122.682 -33.782 90)
		(property "Reference" "TP199"
			(at -1.0668 1.42875 90)
			(unlocked yes)
			(layer "F.SilkS")
			(effects
				(font
					(size 0.635 0.4064)
					(thickness 0.1524)
				)
				(justify left)
			)
		)
		(property "Value" ""
			(at 0 0 90)
			(layer "F.Fab")
			(effects
				(font
					(size 1.27 1.27)
				)
			)
		)
		(property "Device Type" "TP_PIONT-TP010CT020B030_PTH-TPA"
			(at -1.341882 0.996696 90)
			(unlocked yes)
			(layer "F.Fab")
			(hide yes)
			(effects
				(font
					(size 0.7874 0.5842)
					(thickness 0.1524)
				)
				(justify left)
			)
		)
		(duplicate_pad_numbers_are_jumpers no)
		(fp_poly
			(pts
				(arc
					(start 0 0.889)
					(mid 0 -0.889)
					(end 0 0.889)
				)
			)
			(stroke
				(width 0)
				(type default)
			)
			(fill no)
			(layer "B.CrtYd")
		)
		(fp_poly
			(pts
				(arc
					(start 0 0.889)
					(mid 0 -0.889)
					(end 0 0.889)
				)
			)
			(stroke
				(width 0)
				(type default)
			)
			(fill no)
			(layer "F.CrtYd")
		)
		(pad "1" thru_hole circle
			(at 0 0 90)
			(size 0.508 0.508)
			(drill 0.254)
			(layers "*.Cu" "*.Mask")
			(remove_unused_layers no)
			(net "IO_L20P_35")
			(clearance 0.1016)
			(padstack
				(mode front_inner_back)
				(layer "Inner"
					(shape circle)
					(size 0.508 0.508)
					(clearance 0.1016)
				)
				(layer "B.Cu"
					(shape circle)
					(size 0.762 0.762)
					(clearance -0.0254)
				)
			)
		)
	)
)
